(kicad_pcb
	(version 20241229)
	(generator "pcbnew")
	(generator_version "9.0")
	(general
		(thickness 1.62)
		(legacy_teardrops no)
	)
	(paper "A3")
	(title_block
		(title "COM Express 7 Baseboard")
		(date "2025-02-04")
		(rev "1.1.2")
		(company "Antmicro Ltd")
		(comment 1 "www.antmicro.com")
		(comment 9 "footprints 233-236 of 802")
	)
	(layers
		(0 "F.Cu" signal)
		(4 "In1.Cu" signal)
		(6 "In2.Cu" signal)
		(8 "In3.Cu" signal)
		(10 "In4.Cu" signal)
		(12 "In5.Cu" signal)
		(14 "In6.Cu" signal)
		(2 "B.Cu" signal)
		(9 "F.Adhes" user "F.Adhesive")
		(11 "B.Adhes" user "B.Adhesive")
		(13 "F.Paste" user)
		(15 "B.Paste" user)
		(5 "F.SilkS" user "F.Silkscreen")
		(7 "B.SilkS" user "B.Silkscreen")
		(1 "F.Mask" user)
		(3 "B.Mask" user)
		(17 "Dwgs.User" user "User.Drawings")
		(19 "Cmts.User" user "User.Comments")
		(21 "Eco1.User" user "User.Eco1")
		(23 "Eco2.User" user "User.Eco2")
		(25 "Edge.Cuts" user)
		(27 "Margin" user)
		(31 "F.CrtYd" user "F.Courtyard")
		(29 "B.CrtYd" user "B.Courtyard")
		(35 "F.Fab" user)
		(33 "B.Fab" user)
	)
	(footprint "antmicro-footprints:TSSOP-8_3x3mm_P0.65mm"
		(layer "F.Cu")
		(at 124.72 149.26 -90)
		(property "Reference" "U44"
			(at -1.075 -2.655 90)
			(layer "F.SilkS")
			(effects
				(font
					(size 0.7 0.7)
					(thickness 0.15)
				)
				(justify right bottom)
			)
		)
		(property "Value" "NTS0102_TSSOP"
			(at 0 2.8 90)
			(layer "F.Fab")
			(effects
				(font
					(size 0.7 0.7)
					(thickness 0.15)
				)
				(justify right bottom)
			)
		)
		(property "Datasheet" "https://www.mouser.com/datasheet/2/302/NTS0102-1127324.pdf"
			(at 0 0 270)
			(layer "F.Fab")
			(hide yes)
			(effects
				(font
					(size 1.27 1.27)
					(thickness 0.15)
				)
			)
		)
		(property "Author" "Antmicro"
			(at -24.54 273.98 0)
			(layer "F.Fab")
			(hide yes)
			(effects
				(font
					(size 1 1)
					(thickness 0.15)
				)
			)
		)
		(property "License" "Apache-2.0"
			(at -24.54 273.98 0)
			(layer "F.Fab")
			(hide yes)
			(effects
				(font
					(size 1 1)
					(thickness 0.15)
				)
			)
		)
		(property "MPN" "NTS0102DP"
			(at -24.54 273.98 0)
			(layer "F.Fab")
			(hide yes)
			(effects
				(font
					(size 1 1)
					(thickness 0.15)
				)
			)
		)
		(property "Manufacturer" "NXP"
			(at -24.54 273.98 0)
			(layer "F.Fab")
			(hide yes)
			(effects
				(font
					(size 1 1)
					(thickness 0.15)
				)
			)
		)
		(sheetname "KR to SFI #2")
		(sheetfile "kr_sfi.kicad_sch")
		(attr smd)
		(fp_line
			(start -1.55 1.561)
			(end 1.552 1.561)
			(stroke
				(width 0.15)
				(type solid)
			)
			(layer "F.SilkS")
		)
		(fp_line
			(start -1.525 -1.537)
			(end 1.552 -1.539)
			(stroke
				(width 0.15)
				(type solid)
			)
			(layer "F.SilkS")
		)
		(fp_circle
			(center -1.87 -1.4)
			(end -1.82 -1.4)
			(stroke
				(width 0.15)
				(type solid)
			)
			(fill yes)
			(layer "F.SilkS")
		)
		(fp_rect
			(start -3.15 -1.789)
			(end 3.15 1.811)
			(stroke
				(width 0.05)
				(type solid)
			)
			(fill no)
			(layer "F.CrtYd")
		)
		(fp_line
			(start -1.55 1.561)
			(end 1.552 1.561)
			(stroke
				(width 0.15)
				(type solid)
			)
			(layer "F.Fab")
		)
		(fp_line
			(start -1.55 -0.937)
			(end -1.55 1.561)
			(stroke
				(width 0.15)
				(type solid)
			)
			(layer "F.Fab")
		)
		(fp_line
			(start -1.55 -0.937)
			(end -0.949 -1.539)
			(stroke
				(width 0.15)
				(type solid)
			)
			(layer "F.Fab")
		)
		(fp_line
			(start -0.949 -1.539)
			(end 1.552 -1.539)
			(stroke
				(width 0.15)
				(type solid)
			)
			(layer "F.Fab")
		)
		(fp_line
			(start 1.552 -1.539)
			(end 1.552 1.561)
			(stroke
				(width 0.15)
				(type solid)
			)
			(layer "F.Fab")
		)
		(pad "1" smd roundrect
			(at -2.148 -0.962 270)
			(size 1.47 0.4)
			(layers "F.Cu" "F.Mask" "F.Paste")
			(roundrect_rratio 0.25)
			(net 429 "/2xSFP+/MDIO1.MDC")
			(pinfunction "B_{2}")
			(pintype "bidirectional")
			(teardrops
				(best_length_ratio 0.2)
				(max_length 1)
				(best_width_ratio 0.9)
				(max_width 2)
				(curved_edges yes)
				(filter_ratio 0.9)
				(enabled yes)
				(allow_two_segments yes)
				(prefer_zone_connections yes)
			)
		)
		(pad "2" smd roundrect
			(at -2.148 -0.313 270)
			(size 1.47 0.4)
			(layers "F.Cu" "F.Mask" "F.Paste")
			(roundrect_rratio 0.25)
			(net 1 "GND")
			(pinfunction "GND")
			(pintype "power_in")
			(teardrops
				(best_length_ratio 0.2)
				(max_length 1)
				(best_width_ratio 0.9)
				(max_width 2)
				(curved_edges yes)
				(filter_ratio 0.9)
				(enabled yes)
				(allow_two_segments yes)
				(prefer_zone_connections yes)
			)
		)
		(pad "3" smd roundrect
			(at -2.148 0.338 270)
			(size 1.47 0.4)
			(layers "F.Cu" "F.Mask" "F.Paste")
			(roundrect_rratio 0.25)
			(net 78 "+1V8")
			(pinfunction "VCC_{A}")
			(pintype "power_in")
			(teardrops
				(best_length_ratio 0.2)
				(max_length 1)
				(best_width_ratio 0.9)
				(max_width 2)
				(curved_edges yes)
				(filter_ratio 0.9)
				(enabled yes)
				(allow_two_segments yes)
				(prefer_zone_connections yes)
			)
		)
		(pad "4" smd roundrect
			(at -2.148 0.987 270)
			(size 1.47 0.4)
			(layers "F.Cu" "F.Mask" "F.Paste")
			(roundrect_rratio 0.25)
			(net 671 "/2xSFP+/KR to SFI #2/MDC_R")
			(pinfunction "A_{2}")
			(pintype "bidirectional")
			(teardrops
				(best_length_ratio 0.2)
				(max_length 1)
				(best_width_ratio 0.9)
				(max_width 2)
				(curved_edges yes)
				(filter_ratio 0.9)
				(enabled yes)
				(allow_two_segments yes)
				(prefer_zone_connections yes)
			)
		)
		(pad "5" smd roundrect
			(at 2.151 0.987 270)
			(size 1.47 0.4)
			(layers "F.Cu" "F.Mask" "F.Paste")
			(roundrect_rratio 0.25)
			(net 669 "/2xSFP+/KR to SFI #2/MDIO_R")
			(pinfunction "A_{1}")
			(pintype "bidirectional")
			(teardrops
				(best_length_ratio 0.2)
				(max_length 1)
				(best_width_ratio 0.9)
				(max_width 2)
				(curved_edges yes)
				(filter_ratio 0.9)
				(enabled yes)
				(allow_two_segments yes)
				(prefer_zone_connections yes)
			)
		)
		(pad "6" smd roundrect
			(at 2.151 0.338 270)
			(size 1.47 0.4)
			(layers "F.Cu" "F.Mask" "F.Paste")
			(roundrect_rratio 0.25)
			(net 78 "+1V8")
			(pinfunction "OE")
			(pintype "input")
			(teardrops
				(best_length_ratio 0.2)
				(max_length 1)
				(best_width_ratio 0.9)
				(max_width 2)
				(curved_edges yes)
				(filter_ratio 0.9)
				(enabled yes)
				(allow_two_segments yes)
				(prefer_zone_connections yes)
			)
		)
		(pad "7" smd roundrect
			(at 2.151 -0.313 270)
			(size 1.47 0.4)
			(layers "F.Cu" "F.Mask" "F.Paste")
			(roundrect_rratio 0.25)
			(net 2 "+3V3")
			(pinfunction "VCC_{B}")
			(pintype "power_in")
			(teardrops
				(best_length_ratio 0.2)
				(max_length 1)
				(best_width_ratio 0.9)
				(max_width 2)
				(curved_edges yes)
				(filter_ratio 0.9)
				(enabled yes)
				(allow_two_segments yes)
				(prefer_zone_connections yes)
			)
		)
		(pad "8" smd roundrect
			(at 2.151 -0.962 270)
			(size 1.47 0.4)
			(layers "F.Cu" "F.Mask" "F.Paste")
			(roundrect_rratio 0.25)
			(net 490 "/2xSFP+/MDIO1.MDIO")
			(pinfunction "B_{1}")
			(pintype "bidirectional")
			(teardrops
				(best_length_ratio 0.2)
				(max_length 1)
				(best_width_ratio 0.9)
				(max_width 2)
				(curved_edges yes)
				(filter_ratio 0.9)
				(enabled yes)
				(allow_two_segments yes)
				(prefer_zone_connections yes)
			)
		)
	)
	(footprint "antmicro-footprints:DFN-8-1EP_3x2mm_P0.5mm_EP1.36x1.46mm"
		(layer "F.Cu")
		(at 238.5 155.41 90)
		(property "Reference" "U31"
			(at -1.18 2.21 270)
			(layer "F.SilkS")
			(effects
				(font
					(size 0.7 0.7)
					(thickness 0.15)
				)
				(justify left bottom)
			)
		)
		(property "Value" "M24C64-F_DFN8"
			(at 0 2.2 90)
			(layer "F.Fab")
			(effects
				(font
					(size 0.7 0.7)
					(thickness 0.15)
				)
				(justify left bottom)
			)
		)
		(property "Datasheet" "https://eu.mouser.com/datasheet/2/389/cd00259166-1797197.pdf"
			(at 0 0 90)
			(layer "F.Fab")
			(hide yes)
			(effects
				(font
					(size 1.27 1.27)
					(thickness 0.15)
				)
			)
		)
		(property "Author" "Antmicro"
			(at 393.91 -83.09 0)
			(layer "F.Fab")
			(hide yes)
			(effects
				(font
					(size 1 1)
					(thickness 0.15)
				)
			)
		)
		(property "License" "Apache-2.0"
			(at 393.91 -83.09 0)
			(layer "F.Fab")
			(hide yes)
			(effects
				(font
					(size 1 1)
					(thickness 0.15)
				)
			)
		)
		(property "MPN" "M24C64-FMC6TG"
			(at 393.91 -83.09 0)
			(layer "F.Fab")
			(hide yes)
			(effects
				(font
					(size 1 1)
					(thickness 0.15)
				)
			)
		)
		(property "Manufacturer" "STMicroelectronics"
			(at 393.91 -83.09 0)
			(layer "F.Fab")
			(hide yes)
			(effects
				(font
					(size 1 1)
					(thickness 0.15)
				)
			)
		)
		(property ki_fp_filters "UFDFPN8DFN8_2X3_STM UFDFPN8DFN8_2X3_STM-M UFDFPN8DFN8_2X3_STM-L")
		(sheetname "Com Express 7 MGMT")
		(sheetfile "com_express_7_mgmt.kicad_sch")
		(attr smd)
		(fp_line
			(start 1.498 -1.12)
			(end -1.511 -1.12)
			(stroke
				(width 0.15)
				(type solid)
			)
			(layer "F.SilkS")
		)
		(fp_line
			(start -1.501 1.111)
			(end 1.518 1.111)
			(stroke
				(width 0.15)
				(type solid)
			)
			(layer "F.SilkS")
		)
		(fp_circle
			(center -1.751 -1.05)
			(end -1.7 -1.05)
			(stroke
				(width 0.15)
				(type solid)
			)
			(fill yes)
			(layer "F.SilkS")
		)
		(fp_line
			(start 1.889 -1.262)
			(end 1.889 1.228)
			(stroke
				(width 0.05)
				(type solid)
			)
			(layer "F.CrtYd")
		)
		(fp_line
			(start -1.901 -1.262)
			(end 1.889 -1.262)
			(stroke
				(width 0.05)
				(type solid)
			)
			(layer "F.CrtYd")
		)
		(fp_line
			(start 1.889 1.228)
			(end -1.901 1.228)
			(stroke
				(width 0.05)
				(type solid)
			)
			(layer "F.CrtYd")
		)
		(fp_line
			(start -1.901 1.228)
			(end -1.901 -1.262)
			(stroke
				(width 0.05)
				(type solid)
			)
			(layer "F.CrtYd")
		)
		(fp_line
			(start 1.498 -0.999)
			(end -1.491 -0.999)
			(stroke
				(width 0.15)
				(type solid)
			)
			(layer "F.Fab")
		)
		(fp_line
			(start 1.498 -0.999)
			(end 1.498 0.99)
			(stroke
				(width 0.15)
				(type solid)
			)
			(layer "F.Fab")
		)
		(fp_line
			(start -1.501 0.99)
			(end -1.501 -0.989)
			(stroke
				(width 0.15)
				(type solid)
			)
			(layer "F.Fab")
		)
		(fp_line
			(start 1.498 0.999)
			(end -1.501 0.999)
			(stroke
				(width 0.15)
				(type solid)
			)
			(layer "F.Fab")
		)
		(pad "1" smd rect
			(at -1.451 -0.749)
			(size 0.3 0.7)
			(layers "F.Cu" "F.Mask" "F.Paste")
			(net 73 "+3V3_AON")
			(pinfunction "E0")
			(pintype "input")
			(teardrops
				(best_length_ratio 0.2)
				(max_length 1)
				(best_width_ratio 0.9)
				(max_width 2)
				(curved_edges yes)
				(filter_ratio 0.9)
				(enabled yes)
				(allow_two_segments yes)
				(prefer_zone_connections yes)
			)
		)
		(pad "2" smd rect
			(at -1.451 -0.25)
			(size 0.3 0.7)
			(layers "F.Cu" "F.Mask" "F.Paste")
			(net 73 "+3V3_AON")
			(pinfunction "E1")
			(pintype "input")
			(teardrops
				(best_length_ratio 0.2)
				(max_length 1)
				(best_width_ratio 0.9)
				(max_width 2)
				(curved_edges yes)
				(filter_ratio 0.9)
				(enabled yes)
				(allow_two_segments yes)
				(prefer_zone_connections yes)
			)
		)
		(pad "3" smd rect
			(at -1.451 0.249)
			(size 0.3 0.7)
			(layers "F.Cu" "F.Mask" "F.Paste")
			(net 73 "+3V3_AON")
			(pinfunction "E2")
			(pintype "input")
			(teardrops
				(best_length_ratio 0.2)
				(max_length 1)
				(best_width_ratio 0.9)
				(max_width 2)
				(curved_edges yes)
				(filter_ratio 0.9)
				(enabled yes)
				(allow_two_segments yes)
				(prefer_zone_connections yes)
			)
		)
		(pad "4" smd rect
			(at -1.451 0.75)
			(size 0.3 0.7)
			(layers "F.Cu" "F.Mask" "F.Paste")
			(net 1 "GND")
			(pinfunction "VSS")
			(pintype "power_in")
			(teardrops
				(best_length_ratio 0.2)
				(max_length 1)
				(best_width_ratio 0.9)
				(max_width 2)
				(curved_edges yes)
				(filter_ratio 0.9)
				(enabled yes)
				(allow_two_segments yes)
				(prefer_zone_connections yes)
			)
		)
		(pad "5" smd rect
			(at 1.448 0.75)
			(size 0.3 0.7)
			(layers "F.Cu" "F.Mask" "F.Paste")
			(net 372 "/Com Express 7 MGMT/I2C.SDA")
			(pinfunction "SDA")
			(pintype "bidirectional")
			(teardrops
				(best_length_ratio 0.2)
				(max_length 1)
				(best_width_ratio 0.9)
				(max_width 2)
				(curved_edges yes)
				(filter_ratio 0.9)
				(enabled yes)
				(allow_two_segments yes)
				(prefer_zone_connections yes)
			)
		)
		(pad "6" smd rect
			(at 1.448 0.249)
			(size 0.3 0.7)
			(layers "F.Cu" "F.Mask" "F.Paste")
			(net 371 "/Com Express 7 MGMT/I2C.SCL")
			(pinfunction "SCL")
			(pintype "input")
			(teardrops
				(best_length_ratio 0.2)
				(max_length 1)
				(best_width_ratio 0.9)
				(max_width 2)
				(curved_edges yes)
				(filter_ratio 0.9)
				(enabled yes)
				(allow_two_segments yes)
				(prefer_zone_connections yes)
			)
		)
		(pad "7" smd rect
			(at 1.448 -0.25)
			(size 0.3 0.7)
			(layers "F.Cu" "F.Mask" "F.Paste")
			(net 598 "Net-(U31-~{WC})")
			(pinfunction "~{WC}")
			(pintype "input")
			(teardrops
				(best_length_ratio 0.2)
				(max_length 1)
				(best_width_ratio 0.9)
				(max_width 2)
				(curved_edges yes)
				(filter_ratio 0.9)
				(enabled yes)
				(allow_two_segments yes)
				(prefer_zone_connections yes)
			)
		)
		(pad "8" smd rect
			(at 1.448 -0.749)
			(size 0.3 0.7)
			(layers "F.Cu" "F.Mask" "F.Paste")
			(net 73 "+3V3_AON")
			(pinfunction "VCC")
			(pintype "power_in")
			(teardrops
				(best_length_ratio 0.2)
				(max_length 1)
				(best_width_ratio 0.9)
				(max_width 2)
				(curved_edges yes)
				(filter_ratio 0.9)
				(enabled yes)
				(allow_two_segments yes)
				(prefer_zone_connections yes)
			)
		)
		(pad "9" smd rect
			(at 0 0)
			(size 1.5 1.7)
			(layers "F.Cu" "F.Mask" "F.Paste")
			(net 1 "GND")
			(pinfunction "VSS")
			(pintype "passive")
			(solder_paste_margin_ratio -0.1)
			(teardrops
				(best_length_ratio 0.2)
				(max_length 1)
				(best_width_ratio 0.9)
				(max_width 2)
				(curved_edges yes)
				(filter_ratio 0.9)
				(enabled no)
				(allow_two_segments yes)
				(prefer_zone_connections yes)
			)
		)
	)
	(footprint "antmicro-footprints:TP_SMD_0.75mm"
		(layer "F.Cu")
		(at 258.35 128.235 90)
		(property "Reference" "TP43"
			(at -0.425 0.4 180)
			(layer "F.SilkS")
			(effects
				(font
					(size 0.7 0.7)
					(thickness 0.15)
				)
				(justify left bottom)
			)
		)
		(property "Value" "TP_0.75mm_SMD"
			(at 0 1.2 90)
			(layer "F.Fab")
			(effects
				(font
					(size 0.7 0.7)
					(thickness 0.15)
				)
				(justify left bottom)
			)
		)
		(property "Author" "Antmicro"
			(at 386.585 -130.115 0)
			(layer "F.Fab")
			(hide yes)
			(effects
				(font
					(size 1 1)
					(thickness 0.15)
				)
			)
		)
		(property "License" "Apache-2.0"
			(at 386.585 -130.115 0)
			(layer "F.Fab")
			(hide yes)
			(effects
				(font
					(size 1 1)
					(thickness 0.15)
				)
			)
		)
		(property "MPN" ""
			(at 386.585 -130.115 0)
			(layer "F.Fab")
			(hide yes)
			(effects
				(font
					(size 1 1)
					(thickness 0.15)
				)
			)
		)
		(property "Manufacturer" ""
			(at 386.585 -130.115 0)
			(layer "F.Fab")
			(hide yes)
			(effects
				(font
					(size 1 1)
					(thickness 0.15)
				)
			)
		)
		(property "Public" "False"
			(at 386.585 -130.115 0)
			(layer "F.Fab")
			(hide yes)
			(effects
				(font
					(size 1 1)
					(thickness 0.15)
				)
			)
		)
		(sheetname "Com Express 7 MGMT")
		(sheetfile "com_express_7_mgmt.kicad_sch")
		(attr exclude_from_pos_files exclude_from_bom)
		(fp_circle
			(center 0 0)
			(end 0.475 0)
			(stroke
				(width 0.05)
				(type default)
			)
			(fill no)
			(layer "F.CrtYd")
		)
		(pad "1" smd circle
			(at 0 0 90)
			(size 0.75 0.75)
			(layers "F.Cu" "F.Mask")
			(net 708 "Net-(U32-~{MR})")
			(pinfunction "1")
			(pintype "passive")
			(teardrops
				(best_length_ratio 0.4)
				(max_length 1)
				(best_width_ratio 0.9)
				(max_width 2)
				(curved_edges yes)
				(filter_ratio 0.9)
				(enabled yes)
				(allow_two_segments yes)
				(prefer_zone_connections yes)
			)
		)
	)
	(footprint "antmicro-footprints:C_0402_1005Metric"
		(layer "F.Cu")
		(at 306.65 153.83 90)
		(descr "Capacitor SMD 0402")
		(tags "capacitor SMD 0402")
		(property "Reference" "C96"
			(at -0.68 -0.5 90)
			(layer "F.SilkS")
			(effects
				(font
					(size 0.7 0.7)
					(thickness 0.15)
				)
				(justify left bottom)
			)
		)
		(property "Value" "C_100n_0402"
			(at -1.022927 2.155213 90)
			(layer "F.Fab")
			(effects
				(font
					(size 0.7 0.7)
					(thickness 0.15)
				)
				(justify left bottom)
			)
		)
		(property "Datasheet" "https://www.murata.com/products/productdetail?partno=GRM155R61H104KE14%23"
			(at 0 0 90)
			(layer "F.Fab")
			(hide yes)
			(effects
				(font
					(size 1.27 1.27)
					(thickness 0.15)
				)
			)
		)
		(property "Author" "Antmicro"
			(at 460.48 -152.82 0)
			(layer "F.Fab")
			(hide yes)
			(effects
				(font
					(size 1 1)
					(thickness 0.15)
				)
			)
		)
		(property "Dielectric" "X5R"
			(at 460.48 -152.82 0)
			(layer "F.Fab")
			(hide yes)
			(effects
				(font
					(size 1 1)
					(thickness 0.15)
				)
			)
		)
		(property "License" "Apache-2.0"
			(at 460.48 -152.82 0)
			(layer "F.Fab")
			(hide yes)
			(effects
				(font
					(size 1 1)
					(thickness 0.15)
				)
			)
		)
		(property "MPN" "GRM155R61H104KE14D"
			(at 460.48 -152.82 0)
			(layer "F.Fab")
			(hide yes)
			(effects
				(font
					(size 1 1)
					(thickness 0.15)
				)
			)
		)
		(property "Manufacturer" "Murata"
			(at 460.48 -152.82 0)
			(layer "F.Fab")
			(hide yes)
			(effects
				(font
					(size 1 1)
					(thickness 0.15)
				)
			)
		)
		(property "Public" "False"
			(at 460.48 -152.82 0)
			(layer "F.Fab")
			(hide yes)
			(effects
				(font
					(size 1 1)
					(thickness 0.15)
				)
			)
		)
		(property "Val" "100n"
			(at 460.48 -152.82 0)
			(layer "F.Fab")
			(hide yes)
			(effects
				(font
					(size 1 1)
					(thickness 0.15)
				)
			)
		)
		(property "Voltage" "50V"
			(at 460.48 -152.82 0)
			(layer "F.Fab")
			(hide yes)
			(effects
				(font
					(size 1 1)
					(thickness 0.15)
				)
			)
		)
		(sheetname "Com Express 7 MGMT")
		(sheetfile "com_express_7_mgmt.kicad_sch")
		(attr smd)
		(fp_rect
			(start -0.925 -0.47)
			(end 0.925 0.47)
			(stroke
				(width 0.05)
				(type default)
			)
			(fill no)
			(layer "F.CrtYd")
		)
		(fp_line
			(start 0.504 -0.25)
			(end 0.504 0.248)
			(stroke
				(width 0.15)
				(type solid)
			)
			(layer "F.Fab")
		)
		(fp_line
			(start -0.494 -0.25)
			(end 0.504 -0.25)
			(stroke
				(width 0.15)
				(type solid)
			)
			(layer "F.Fab")
		)
		(fp_line
			(start 0.504 0.248)
			(end -0.494 0.248)
			(stroke
				(width 0.15)
				(type solid)
			)
			(layer "F.Fab")
		)
		(fp_line
			(start -0.494 0.248)
			(end -0.494 -0.25)
			(stroke
				(width 0.15)
				(type solid)
			)
			(layer "F.Fab")
		)
		(pad "1" smd roundrect
			(at -0.48 0 90)
			(size 0.59 0.64)
			(layers "F.Cu" "F.Mask" "F.Paste")
			(roundrect_rratio 0.25)
			(net 1 "GND")
			(pintype "passive")
			(teardrops
				(best_length_ratio 0.2)
				(max_length 1)
				(best_width_ratio 0.9)
				(max_width 2)
				(curved_edges yes)
				(filter_ratio 0.9)
				(enabled yes)
				(allow_two_segments yes)
				(prefer_zone_connections yes)
			)
		)
		(pad "2" smd roundrect
			(at 0.48 0 90)
			(size 0.59 0.64)
			(layers "F.Cu" "F.Mask" "F.Paste")
			(roundrect_rratio 0.25)
			(net 73 "+3V3_AON")
			(pintype "passive")
			(teardrops
				(best_length_ratio 0.2)
				(max_length 1)
				(best_width_ratio 0.9)
				(max_width 2)
				(curved_edges yes)
				(filter_ratio 0.9)
				(enabled yes)
				(allow_two_segments yes)
				(prefer_zone_connections yes)
			)
		)
	)
)
